(kicad_pcb
	(version 20260206)
	(generator "pcbnew")
	(generator_version "10.0")
	(general
		(thickness 1.6)
		(legacy_teardrops no)
	)
	(paper "A4")
	(title_block
		(title "04192023_DAF0TMB3IC0_F0TG_MB_C_brd_V02_OCP.brd")
		(comment 1 "Grand Teton / footprint 3955 of 8354 (U25), pads 4222-4338 of 6102")
	)
	(layers
		(0 "F.Cu" signal "TOP")
		(4 "In1.Cu" signal "GND")
		(6 "In2.Cu" signal "IN1")
		(8 "In3.Cu" signal "GND1")
		(10 "In4.Cu" signal "IN2")
		(12 "In5.Cu" signal "GND2")
		(14 "In6.Cu" signal "IN3")
		(16 "In7.Cu" signal "GND3")
		(18 "In8.Cu" signal "VCC")
		(20 "In9.Cu" signal "VCC1")
		(22 "In10.Cu" signal "GND4")
		(24 "In11.Cu" signal "IN4")
		(26 "In12.Cu" signal "GND5")
		(28 "In13.Cu" signal "IN5")
		(30 "In14.Cu" signal "GND6")
		(32 "In15.Cu" signal "IN6")
		(34 "In16.Cu" signal "GND7")
		(2 "B.Cu" signal "BOTTOM")
		(9 "F.Adhes" user "F.Adhesive")
		(11 "B.Adhes" user "B.Adhesive")
		(13 "F.Paste" user "Package Geometry/Pastemask Top")
		(15 "B.Paste" user "Package Geometry/Pastemask Bottom")
		(5 "F.SilkS" user "Ref Des/Silkscreen Top")
		(7 "B.SilkS" user "Ref Des/Silkscreen Bottom")
		(1 "F.Mask" user "Board Geometry/Soldermask Top")
		(3 "B.Mask" user "Board Geometry/Soldermask Bottom")
		(17 "Dwgs.User" user "User.Drawings")
		(19 "Cmts.User" user "User.Comments")
		(21 "Eco1.User" user "User.Eco1")
		(23 "Eco2.User" user "User.Eco2")
		(25 "Edge.Cuts" user "Board Geometry/Outline")
		(27 "Margin" user)
		(31 "F.CrtYd" user "Package Geometry/Place Bound Top")
		(29 "B.CrtYd" user "Package Geometry/Place Bound Bottom")
		(35 "F.Fab" user "Ref Des/Assembly Top")
		(33 "B.Fab" user "Ref Des/Assembly Bottom")
	)
	(footprint ""
		(layer "F.Cu")
		(at 359.867962 -258.880102 180)
		(property "Reference" "U25"
			(at -45.78477 -62.086744 0)
			(unlocked yes)
			(layer "F.SilkS")
			(effects
				(font
					(size 0.7874 0.5842)
					(thickness 0.1524)
				)
			)
		)
		(property "Value" ""
			(at 0 0 180)
			(layer "F.Fab")
			(effects
				(font
					(size 1.27 1.27)
				)
			)
		)
		(duplicate_pad_numbers_are_jumpers no)
		(pad "CY48" smd circle
			(at 9.249918 29.51988 180)
			(size 0.450088 0.450088)
			(layers "F.Cu" "F.Mask" "F.Paste")
			(net "GND")
		)
		(pad "CY49" smd circle
			(at 10.189972 29.51988 180)
			(size 0.450088 0.450088)
			(layers "F.Cu" "F.Mask" "F.Paste")
			(net "GND")
		)
		(pad "CY50" smd circle
			(at 11.130026 29.51988 180)
			(size 0.450088 0.450088)
			(layers "F.Cu" "F.Mask" "F.Paste")
			(net "GND")
		)
		(pad "CY51" smd circle
			(at 12.07008 29.51988 180)
			(size 0.450088 0.450088)
			(layers "F.Cu" "F.Mask" "F.Paste")
			(net "GND")
		)
		(pad "CY52" smd circle
			(at 13.00988 29.51988 180)
			(size 0.450088 0.450088)
			(layers "F.Cu" "F.Mask" "F.Paste")
			(net "GND")
		)
		(pad "CY53" smd circle
			(at 13.949934 29.51988 180)
			(size 0.450088 0.450088)
			(layers "F.Cu" "F.Mask" "F.Paste")
			(net "GND")
		)
		(pad "CY54" smd circle
			(at 14.889988 29.51988 180)
			(size 0.450088 0.450088)
			(layers "F.Cu" "F.Mask" "F.Paste")
			(net "PVDDIO_P0")
		)
		(pad "CY55" smd circle
			(at 15.830042 29.51988 180)
			(size 0.450088 0.450088)
			(layers "F.Cu" "F.Mask" "F.Paste")
			(net "M_C_CPU0_SB_DQ<23>")
		)
		(pad "CY56" smd circle
			(at 16.770096 29.51988 180)
			(size 0.450088 0.450088)
			(layers "F.Cu" "F.Mask" "F.Paste")
			(net "M_C_CPU0_SB_DQ<24>")
		)
		(pad "CY57" smd circle
			(at 17.709896 29.51988 180)
			(size 0.450088 0.450088)
			(layers "F.Cu" "F.Mask" "F.Paste")
			(net "GND")
		)
		(pad "CY58" smd circle
			(at 18.64995 29.51988 180)
			(size 0.450088 0.450088)
			(layers "F.Cu" "F.Mask" "F.Paste")
			(net "M_D_CPU0_SB_DQ<23>")
		)
		(pad "CY59" smd circle
			(at 19.590004 29.51988 180)
			(size 0.450088 0.450088)
			(layers "F.Cu" "F.Mask" "F.Paste")
			(net "GND")
		)
		(pad "CY60" smd circle
			(at 20.530058 29.51988 180)
			(size 0.450088 0.450088)
			(layers "F.Cu" "F.Mask" "F.Paste")
			(net "M_D_CPU0_SB_DQ<24>")
		)
		(pad "CY61" smd circle
			(at 21.470112 29.51988 180)
			(size 0.450088 0.450088)
			(layers "F.Cu" "F.Mask" "F.Paste")
			(net "GND")
		)
		(pad "CY62" smd circle
			(at 22.409912 29.51988 180)
			(size 0.450088 0.450088)
			(layers "F.Cu" "F.Mask" "F.Paste")
			(net "M_B_CPU0_SB_DQ<23>")
		)
		(pad "CY63" smd circle
			(at 23.349966 29.51988 180)
			(size 0.450088 0.450088)
			(layers "F.Cu" "F.Mask" "F.Paste")
			(net "M_B_CPU0_SB_DQ<24>")
		)
		(pad "CY64" smd circle
			(at 24.29002 29.51988 180)
			(size 0.450088 0.450088)
			(layers "F.Cu" "F.Mask" "F.Paste")
			(net "GND")
		)
		(pad "CY65" smd circle
			(at 25.230074 29.51988 180)
			(size 0.450088 0.450088)
			(layers "F.Cu" "F.Mask" "F.Paste")
			(net "M_F_CPU0_SB_DQ<23>")
		)
		(pad "CY66" smd circle
			(at 26.170128 29.51988 180)
			(size 0.450088 0.450088)
			(layers "F.Cu" "F.Mask" "F.Paste")
			(net "GND")
		)
		(pad "CY67" smd circle
			(at 27.109928 29.51988 180)
			(size 0.450088 0.450088)
			(layers "F.Cu" "F.Mask" "F.Paste")
			(net "M_F_CPU0_SB_DQ<24>")
		)
		(pad "CY68" smd circle
			(at 28.049982 29.51988 180)
			(size 0.450088 0.450088)
			(layers "F.Cu" "F.Mask" "F.Paste")
			(net "GND")
		)
		(pad "CY69" smd circle
			(at 28.990036 29.51988 180)
			(size 0.450088 0.450088)
			(layers "F.Cu" "F.Mask" "F.Paste")
			(net "M_E_CPU0_SB_DQ<23>")
		)
		(pad "CY70" smd circle
			(at 29.93009 29.51988 180)
			(size 0.450088 0.450088)
			(layers "F.Cu" "F.Mask" "F.Paste")
			(net "M_E_CPU0_SB_DQ<24>")
		)
		(pad "CY71" smd circle
			(at 30.86989 29.51988 180)
			(size 0.450088 0.450088)
			(layers "F.Cu" "F.Mask" "F.Paste")
			(net "GND")
		)
		(pad "CY72" smd circle
			(at 31.809944 29.51988 180)
			(size 0.450088 0.450088)
			(layers "F.Cu" "F.Mask" "F.Paste")
			(net "M_A_CPU0_SB_DQ<23>")
		)
		(pad "CY73" smd circle
			(at 32.749998 29.51988 180)
			(size 0.450088 0.450088)
			(layers "F.Cu" "F.Mask" "F.Paste")
			(net "GND")
		)
		(pad "CY74" smd circle
			(at 33.690052 29.51988 180)
			(size 0.450088 0.450088)
			(layers "F.Cu" "F.Mask" "F.Paste")
			(net "M_A_CPU0_SB_DQ<24>")
		)
		(pad "D2" smd circle
			(at -33.690052 -34.379916 180)
			(size 0.450088 0.450088)
			(layers "F.Cu" "F.Mask" "F.Paste")
			(net "GND")
		)
		(pad "D3" smd circle
			(at -32.749998 -34.379916 180)
			(size 0.450088 0.450088)
			(layers "F.Cu" "F.Mask" "F.Paste")
			(net "GND")
		)
		(pad "D4" smd circle
			(at -31.809944 -34.379916 180)
			(size 0.450088 0.450088)
			(layers "F.Cu" "F.Mask" "F.Paste")
			(net "Net_1934")
		)
		(pad "D5" smd circle
			(at -30.86989 -34.379916 180)
			(size 0.450088 0.450088)
			(layers "F.Cu" "F.Mask" "F.Paste")
			(net "GND")
		)
		(pad "D6" smd circle
			(at -29.93009 -34.379916 180)
			(size 0.450088 0.450088)
			(layers "F.Cu" "F.Mask" "F.Paste")
			(net "GND")
		)
		(pad "D7" smd circle
			(at -28.990036 -34.379916 180)
			(size 0.450088 0.450088)
			(layers "F.Cu" "F.Mask" "F.Paste")
			(net "TP_CPU0_TEST47_IOD1")
		)
		(pad "D8" smd circle
			(at -28.049982 -34.379916 180)
			(size 0.450088 0.450088)
			(layers "F.Cu" "F.Mask" "F.Paste")
			(net "Net_1939")
		)
		(pad "D9" smd circle
			(at -27.109928 -34.379916 180)
			(size 0.450088 0.450088)
			(layers "F.Cu" "F.Mask" "F.Paste")
			(net "GND")
		)
		(pad "D10" smd circle
			(at -26.170128 -34.379916 180)
			(size 0.450088 0.450088)
			(layers "F.Cu" "F.Mask" "F.Paste")
			(net "GND")
		)
		(pad "D11" smd circle
			(at -25.230074 -34.379916 180)
			(size 0.450088 0.450088)
			(layers "F.Cu" "F.Mask" "F.Paste")
			(net "Net_1930")
		)
		(pad "D12" smd circle
			(at -24.29002 -34.379916 180)
			(size 0.450088 0.450088)
			(layers "F.Cu" "F.Mask" "F.Paste")
			(net "GND")
		)
		(pad "D13" smd circle
			(at -23.349966 -34.379916 180)
			(size 0.450088 0.450088)
			(layers "F.Cu" "F.Mask" "F.Paste")
			(net "GND")
		)
		(pad "D14" smd circle
			(at -22.409912 -34.379916 180)
			(size 0.450088 0.450088)
			(layers "F.Cu" "F.Mask" "F.Paste")
			(net "SMB_CPU0_SEC_SDA")
		)
		(pad "D15" smd circle
			(at -21.470112 -34.379916 180)
			(size 0.450088 0.450088)
			(layers "F.Cu" "F.Mask" "F.Paste")
			(net "Net_1881")
		)
		(pad "D16" smd circle
			(at -20.530058 -34.379916 180)
			(size 0.450088 0.450088)
			(layers "F.Cu" "F.Mask" "F.Paste")
			(net "GND")
		)
		(pad "D17" smd circle
			(at -19.590004 -34.379916 180)
			(size 0.450088 0.450088)
			(layers "F.Cu" "F.Mask" "F.Paste")
			(net "GND")
		)
		(pad "D18" smd circle
			(at -18.64995 -34.379916 180)
			(size 0.450088 0.450088)
			(layers "F.Cu" "F.Mask" "F.Paste")
			(net "RST_CPU0_PERST0_N")
		)
		(pad "D19" smd circle
			(at -17.709896 -34.379916 180)
			(size 0.450088 0.450088)
			(layers "F.Cu" "F.Mask" "F.Paste")
			(net "GND")
		)
		(pad "D20" smd circle
			(at -16.770096 -34.379916 180)
			(size 0.450088 0.450088)
			(layers "F.Cu" "F.Mask" "F.Paste")
			(net "GND")
		)
		(pad "D21" smd circle
			(at -15.830042 -34.379916 180)
			(size 0.450088 0.450088)
			(layers "F.Cu" "F.Mask" "F.Paste")
			(net "GND")
		)
		(pad "D22" smd circle
			(at -14.889988 -34.379916 180)
			(size 0.450088 0.450088)
			(layers "F.Cu" "F.Mask" "F.Paste")
			(net "Net_1931")
		)
		(pad "D23" smd circle
			(at -13.949934 -34.379916 180)
			(size 0.450088 0.450088)
			(layers "F.Cu" "F.Mask" "F.Paste")
			(net "Net_1953")
		)
		(pad "D24" smd circle
			(at -13.00988 -34.379916 180)
			(size 0.450088 0.450088)
			(layers "F.Cu" "F.Mask" "F.Paste")
			(net "GND")
		)
		(pad "D25" smd circle
			(at -12.07008 -34.379916 180)
			(size 0.450088 0.450088)
			(layers "F.Cu" "F.Mask" "F.Paste")
			(net "GND")
		)
		(pad "D26" smd circle
			(at -11.130026 -34.379916 180)
			(size 0.450088 0.450088)
			(layers "F.Cu" "F.Mask" "F.Paste")
			(net "GND")
		)
		(pad "D27" smd circle
			(at -10.189972 -34.379916 180)
			(size 0.450088 0.450088)
			(layers "F.Cu" "F.Mask" "F.Paste")
			(net "GND")
		)
		(pad "D28" smd circle
			(at -9.249918 -34.379916 180)
			(size 0.450088 0.450088)
			(layers "F.Cu" "F.Mask" "F.Paste")
			(net "GND")
		)
		(pad "D29" smd circle
			(at -8.310118 -34.379916 180)
			(size 0.450088 0.450088)
			(layers "F.Cu" "F.Mask" "F.Paste")
			(net "GND")
		)
		(pad "D30" smd circle
			(at -7.370064 -34.379916 180)
			(size 0.450088 0.450088)
			(layers "F.Cu" "F.Mask" "F.Paste")
			(net "GND")
		)
		(pad "D31" smd circle
			(at -6.43001 -34.379916 180)
			(size 0.450088 0.450088)
			(layers "F.Cu" "F.Mask" "F.Paste")
			(net "GND")
		)
		(pad "D32" smd circle
			(at -5.489956 -34.379916 180)
			(size 0.450088 0.450088)
			(layers "F.Cu" "F.Mask" "F.Paste")
			(net "NC_CPU0_AZ_SYNC")
		)
		(pad "D33" smd circle
			(at -4.549902 -34.379916 180)
			(size 0.450088 0.450088)
			(layers "F.Cu" "F.Mask" "F.Paste")
			(net "NC_CPU0_AZ_SDIN1")
		)
		(pad "D34" smd circle
			(at -3.610102 -34.379916 180)
			(size 0.450088 0.450088)
			(layers "F.Cu" "F.Mask" "F.Paste")
			(net "Net_1932")
		)
		(pad "D35" smd circle
			(at -2.670048 -34.379916 180)
			(size 0.450088 0.450088)
			(layers "F.Cu" "F.Mask" "F.Paste")
			(net "GND")
		)
		(pad "D36" smd circle
			(at -1.729994 -34.379916 180)
			(size 0.450088 0.450088)
			(layers "F.Cu" "F.Mask" "F.Paste")
			(net "Net_1933")
		)
		(pad "D37" smd circle
			(at -0.78994 -34.379916 180)
			(size 0.450088 0.450088)
			(layers "F.Cu" "F.Mask" "F.Paste")
			(net "GND")
		)
		(pad "D39" smd circle
			(at 1.089914 -34.379916 180)
			(size 0.450088 0.450088)
			(layers "F.Cu" "F.Mask" "F.Paste")
			(net "GND")
		)
		(pad "D40" smd circle
			(at 2.029968 -34.379916 180)
			(size 0.450088 0.450088)
			(layers "F.Cu" "F.Mask" "F.Paste")
			(net "GND")
		)
		(pad "D41" smd circle
			(at 2.970022 -34.379916 180)
			(size 0.450088 0.450088)
			(layers "F.Cu" "F.Mask" "F.Paste")
			(net "GND")
		)
		(pad "D42" smd circle
			(at 3.910076 -34.379916 180)
			(size 0.450088 0.450088)
			(layers "F.Cu" "F.Mask" "F.Paste")
			(net "GND")
		)
		(pad "D43" smd circle
			(at 4.849876 -34.379916 180)
			(size 0.450088 0.450088)
			(layers "F.Cu" "F.Mask" "F.Paste")
			(net "GND")
		)
		(pad "D44" smd circle
			(at 5.78993 -34.379916 180)
			(size 0.450088 0.450088)
			(layers "F.Cu" "F.Mask" "F.Paste")
			(net "GND")
		)
		(pad "D45" smd circle
			(at 6.729984 -34.379916 180)
			(size 0.450088 0.450088)
			(layers "F.Cu" "F.Mask" "F.Paste")
			(net "GND")
		)
		(pad "D46" smd circle
			(at 7.670038 -34.379916 180)
			(size 0.450088 0.450088)
			(layers "F.Cu" "F.Mask" "F.Paste")
			(net "GND")
		)
		(pad "D47" smd circle
			(at 8.610092 -34.379916 180)
			(size 0.450088 0.450088)
			(layers "F.Cu" "F.Mask" "F.Paste")
			(net "GND")
		)
		(pad "D48" smd circle
			(at 9.549892 -34.379916 180)
			(size 0.450088 0.450088)
			(layers "F.Cu" "F.Mask" "F.Paste")
			(net "GND")
		)
		(pad "D49" smd circle
			(at 10.489946 -34.379916 180)
			(size 0.450088 0.450088)
			(layers "F.Cu" "F.Mask" "F.Paste")
			(net "GND")
		)
		(pad "D50" smd circle
			(at 11.43 -34.379916 180)
			(size 0.450088 0.450088)
			(layers "F.Cu" "F.Mask" "F.Paste")
			(net "GND")
		)
		(pad "D51" smd circle
			(at 12.370054 -34.379916 180)
			(size 0.450088 0.450088)
			(layers "F.Cu" "F.Mask" "F.Paste")
			(net "GND")
		)
		(pad "D52" smd circle
			(at 13.310108 -34.379916 180)
			(size 0.450088 0.450088)
			(layers "F.Cu" "F.Mask" "F.Paste")
			(net "GND")
		)
		(pad "D53" smd circle
			(at 14.249908 -34.379916 180)
			(size 0.450088 0.450088)
			(layers "F.Cu" "F.Mask" "F.Paste")
			(net "GND")
		)
		(pad "D54" smd circle
			(at 15.189962 -34.379916 180)
			(size 0.450088 0.450088)
			(layers "F.Cu" "F.Mask" "F.Paste")
			(net "GND")
		)
		(pad "D55" smd circle
			(at 16.130016 -34.379916 180)
			(size 0.450088 0.450088)
			(layers "F.Cu" "F.Mask" "F.Paste")
			(net "PVDDCR_CPU0_P0")
		)
		(pad "D56" smd circle
			(at 17.07007 -34.379916 180)
			(size 0.450088 0.450088)
			(layers "F.Cu" "F.Mask" "F.Paste")
			(net "PVDDCR_CPU0_P0")
		)
		(pad "D57" smd circle
			(at 18.010124 -34.379916 180)
			(size 0.450088 0.450088)
			(layers "F.Cu" "F.Mask" "F.Paste")
			(net "GND")
		)
		(pad "D58" smd circle
			(at 18.949924 -34.379916 180)
			(size 0.450088 0.450088)
			(layers "F.Cu" "F.Mask" "F.Paste")
			(net "Net_1935")
		)
		(pad "D59" smd circle
			(at 19.889978 -34.379916 180)
			(size 0.450088 0.450088)
			(layers "F.Cu" "F.Mask" "F.Paste")
			(net "GND")
		)
		(pad "D60" smd circle
			(at 20.830032 -34.379916 180)
			(size 0.450088 0.450088)
			(layers "F.Cu" "F.Mask" "F.Paste")
			(net "GND")
		)
		(pad "D61" smd circle
			(at 21.770086 -34.379916 180)
			(size 0.450088 0.450088)
			(layers "F.Cu" "F.Mask" "F.Paste")
			(net "GND")
		)
		(pad "D62" smd circle
			(at 22.709886 -34.379916 180)
			(size 0.450088 0.450088)
			(layers "F.Cu" "F.Mask" "F.Paste")
			(net "Net_1936")
		)
		(pad "D63" smd circle
			(at 23.64994 -34.379916 180)
			(size 0.450088 0.450088)
			(layers "F.Cu" "F.Mask" "F.Paste")
			(net "GND")
		)
		(pad "D64" smd circle
			(at 24.589994 -34.379916 180)
			(size 0.450088 0.450088)
			(layers "F.Cu" "F.Mask" "F.Paste")
			(net "GND")
		)
		(pad "D65" smd circle
			(at 25.530048 -34.379916 180)
			(size 0.450088 0.450088)
			(layers "F.Cu" "F.Mask" "F.Paste")
			(net "Net_1937")
		)
		(pad "D66" smd circle
			(at 26.470102 -34.379916 180)
			(size 0.450088 0.450088)
			(layers "F.Cu" "F.Mask" "F.Paste")
			(net "GND")
		)
		(pad "D67" smd circle
			(at 27.409902 -34.379916 180)
			(size 0.450088 0.450088)
			(layers "F.Cu" "F.Mask" "F.Paste")
			(net "GND")
		)
		(pad "D68" smd circle
			(at 28.349956 -34.379916 180)
			(size 0.450088 0.450088)
			(layers "F.Cu" "F.Mask" "F.Paste")
			(net "CPU0_CORETYPE2")
		)
		(pad "D69" smd circle
			(at 29.29001 -34.379916 180)
			(size 0.450088 0.450088)
			(layers "F.Cu" "F.Mask" "F.Paste")
			(net "PWRGD_CPU0_PWROK")
		)
		(pad "D70" smd circle
			(at 30.230064 -34.379916 180)
			(size 0.450088 0.450088)
			(layers "F.Cu" "F.Mask" "F.Paste")
			(net "GND")
		)
		(pad "D71" smd circle
			(at 31.170118 -34.379916 180)
			(size 0.450088 0.450088)
			(layers "F.Cu" "F.Mask" "F.Paste")
			(net "GND")
		)
		(pad "D72" smd circle
			(at 32.109918 -34.379916 180)
			(size 0.450088 0.450088)
			(layers "F.Cu" "F.Mask" "F.Paste")
			(net "Net_1938")
		)
		(pad "D73" smd circle
			(at 33.049972 -34.379916 180)
			(size 0.450088 0.450088)
			(layers "F.Cu" "F.Mask" "F.Paste")
			(net "GND")
		)
		(pad "D74" smd circle
			(at 33.990026 -34.379916 180)
			(size 0.450088 0.450088)
			(layers "F.Cu" "F.Mask" "F.Paste")
			(net "GND")
		)
		(pad "DA1" smd circle
			(at -34.459926 30.329886 180)
			(size 0.450088 0.450088)
			(layers "F.Cu" "F.Mask" "F.Paste")
			(net "GND")
		)
		(pad "DA2" smd circle
			(at -33.519872 30.329886 180)
			(size 0.450088 0.450088)
			(layers "F.Cu" "F.Mask" "F.Paste")
			(net "M_G_CPU0_SB_DQ<26>")
		)
		(pad "DA3" smd circle
			(at -32.580072 30.329886 180)
			(size 0.450088 0.450088)
			(layers "F.Cu" "F.Mask" "F.Paste")
			(net "M_G_CPU0_SB_DQ<25>")
		)
		(pad "DA4" smd circle
			(at -31.640018 30.329886 180)
			(size 0.450088 0.450088)
			(layers "F.Cu" "F.Mask" "F.Paste")
			(net "GND")
		)
		(pad "DA5" smd circle
			(at -30.699964 30.329886 180)
			(size 0.450088 0.450088)
			(layers "F.Cu" "F.Mask" "F.Paste")
			(net "M_K_CPU0_SB_DQ<26>")
		)
		(pad "DA6" smd circle
			(at -29.75991 30.329886 180)
			(size 0.450088 0.450088)
			(layers "F.Cu" "F.Mask" "F.Paste")
			(net "GND")
		)
		(pad "DA7" smd circle
			(at -28.82011 30.329886 180)
			(size 0.450088 0.450088)
			(layers "F.Cu" "F.Mask" "F.Paste")
			(net "M_K_CPU0_SB_DQ<25>")
		)
		(pad "DA8" smd circle
			(at -27.880056 30.329886 180)
			(size 0.450088 0.450088)
			(layers "F.Cu" "F.Mask" "F.Paste")
			(net "GND")
		)
		(pad "DA9" smd circle
			(at -26.940002 30.329886 180)
			(size 0.450088 0.450088)
			(layers "F.Cu" "F.Mask" "F.Paste")
			(net "M_L_CPU0_SB_DQ<26>")
		)
		(pad "DA10" smd circle
			(at -25.999948 30.329886 180)
			(size 0.450088 0.450088)
			(layers "F.Cu" "F.Mask" "F.Paste")
			(net "M_L_CPU0_SB_DQ<25>")
		)
		(pad "DA11" smd circle
			(at -25.059894 30.329886 180)
			(size 0.450088 0.450088)
			(layers "F.Cu" "F.Mask" "F.Paste")
			(net "GND")
		)
		(pad "DA12" smd circle
			(at -24.120094 30.329886 180)
			(size 0.450088 0.450088)
			(layers "F.Cu" "F.Mask" "F.Paste")
			(net "M_H_CPU0_SB_DQ<26>")
		)
		(pad "DA13" smd circle
			(at -23.18004 30.329886 180)
			(size 0.450088 0.450088)
			(layers "F.Cu" "F.Mask" "F.Paste")
			(net "GND")
		)
		(pad "DA14" smd circle
			(at -22.239986 30.329886 180)
			(size 0.450088 0.450088)
			(layers "F.Cu" "F.Mask" "F.Paste")
			(net "M_H_CPU0_SB_DQ<25>")
		)
		(pad "DA15" smd circle
			(at -21.299932 30.329886 180)
			(size 0.450088 0.450088)
			(layers "F.Cu" "F.Mask" "F.Paste")
			(net "GND")
		)
		(pad "DA16" smd circle
			(at -20.359878 30.329886 180)
			(size 0.450088 0.450088)
			(layers "F.Cu" "F.Mask" "F.Paste")
			(net "M_J_CPU0_SB_DQ<26>")
		)
		(pad "DA17" smd circle
			(at -19.420078 30.329886 180)
			(size 0.450088 0.450088)
			(layers "F.Cu" "F.Mask" "F.Paste")
			(net "M_J_CPU0_SB_DQ<25>")
		)
		(pad "DA18" smd circle
			(at -18.480024 30.329886 180)
			(size 0.450088 0.450088)
			(layers "F.Cu" "F.Mask" "F.Paste")
			(net "GND")
		)
	)
)
